# S9S_MB_2U (Grand Teton) — schematic netlist excerpt (pin names and nets, part order shuffled) for the footprints in the layout excerpt that follows; sources: Cadence DE-HDL packaged netlist, KiCad conversion of 03242023_DA0F0TMBIJ0_F0T_Motherboard_J_brd_V01_OCP.brd

U75  74LVC1G17GW  IC  pkg TSSOP5  page 155
  NC  = NC
  A  = RST_HP_OCP_V3_1_N
  GND  = GND
  Y  = RST_OCP_V3_1_BUF_N
  VCC  = P3V3_AUX

PR3841  Q_RES  120K 1% CHIP  pkg 0402LF  page 157 : A = P12V_AUX ; B = P12V_OCP_OV_FB_1

(kicad_pcb
	(version 20260206)
	(generator "pcbnew")
	(generator_version "10.0")
	(general
		(thickness 1.6)
		(legacy_teardrops no)
	)
	(paper "A4")
	(title_block
		(title "03242023_DA0F0TMBIJ0_F0T_Motherboard_J_brd_V01_OCP.brd")
		(comment 1 "Grand Teton / footprints 4073-4074 of 6105")
	)
	(layers
		(0 "F.Cu" signal "TOP")
		(4 "In1.Cu" signal "GND")
		(6 "In2.Cu" signal "IN1")
		(8 "In3.Cu" signal "GND1")
		(10 "In4.Cu" signal "IN2")
		(12 "In5.Cu" signal "GND2")
		(14 "In6.Cu" signal "IN3")
		(16 "In7.Cu" signal "GND3")
		(18 "In8.Cu" signal "VCC")
		(20 "In9.Cu" signal "VCC1")
		(22 "In10.Cu" signal "GND4")
		(24 "In11.Cu" signal "IN4")
		(26 "In12.Cu" signal "GND5")
		(28 "In13.Cu" signal "IN5")
		(30 "In14.Cu" signal "GND6")
		(32 "In15.Cu" signal "IN6")
		(34 "In16.Cu" signal "GND7")
		(2 "B.Cu" signal "BOTTOM")
		(9 "F.Adhes" user "F.Adhesive")
		(11 "B.Adhes" user "B.Adhesive")
		(13 "F.Paste" user "Package Geometry/Pastemask Top")
		(15 "B.Paste" user "Package Geometry/Pastemask Bottom")
		(5 "F.SilkS" user "Ref Des/Silkscreen Top")
		(7 "B.SilkS" user "Ref Des/Silkscreen Bottom")
		(1 "F.Mask" user "Board Geometry/Soldermask Top")
		(3 "B.Mask" user "Board Geometry/Soldermask Bottom")
		(17 "Dwgs.User" user "User.Drawings")
		(19 "Cmts.User" user "User.Comments")
		(21 "Eco1.User" user "User.Eco1")
		(23 "Eco2.User" user "User.Eco2")
		(25 "Edge.Cuts" user "Board Geometry/Outline")
		(27 "Margin" user)
		(31 "F.CrtYd" user "Package Geometry/Place Bound Top")
		(29 "B.CrtYd" user "Package Geometry/Place Bound Bottom")
		(35 "F.Fab" user "Ref Des/Assembly Top")
		(33 "B.Fab" user "Ref Des/Assembly Bottom")
	)
	(footprint ""
		(layer "F.Cu")
		(at 437.542432 -27.275536 90)
		(property "Reference" "PR3841"
			(at 0 0 90)
			(layer "F.SilkS")
			(hide yes)
			(effects
				(font
					(size 1.27 1.27)
				)
			)
		)
		(property "Value" ""
			(at 0 0 90)
			(layer "F.Fab")
			(effects
				(font
					(size 1.27 1.27)
				)
			)
		)
		(duplicate_pad_numbers_are_jumpers no)
		(fp_line
			(start 0.7874 -0.4064)
			(end 0.7874 0.4064)
			(stroke
				(width 0.1524)
				(type default)
			)
			(layer "F.SilkS")
		)
		(fp_line
			(start -0.7874 -0.4064)
			(end 0.7874 -0.4064)
			(stroke
				(width 0.1524)
				(type default)
			)
			(layer "F.SilkS")
		)
		(fp_line
			(start 0.7874 0.4064)
			(end -0.7874 0.4064)
			(stroke
				(width 0.1524)
				(type default)
			)
			(layer "F.SilkS")
		)
		(fp_line
			(start -0.7874 0.4064)
			(end -0.7874 -0.4064)
			(stroke
				(width 0.1524)
				(type default)
			)
			(layer "F.SilkS")
		)
		(fp_line
			(start -0.12065 -0.305054)
			(end -0.12065 -0.2794)
			(stroke
				(width 0.1)
				(type default)
			)
			(layer "F.Fab")
		)
		(fp_line
			(start -0.67945 -0.305054)
			(end -0.12065 -0.305054)
			(stroke
				(width 0.1)
				(type default)
			)
			(layer "F.Fab")
		)
		(fp_line
			(start 0.67945 -0.3048)
			(end 0.67945 0.3048)
			(stroke
				(width 0.1)
				(type default)
			)
			(layer "F.Fab")
		)
		(fp_line
			(start 0.12065 -0.3048)
			(end 0.67945 -0.3048)
			(stroke
				(width 0.1)
				(type default)
			)
			(layer "F.Fab")
		)
		(fp_line
			(start 0.12065 -0.2794)
			(end 0.12065 -0.3048)
			(stroke
				(width 0.1)
				(type default)
			)
			(layer "F.Fab")
		)
		(fp_line
			(start -0.12065 -0.2794)
			(end 0.12065 -0.2794)
			(stroke
				(width 0.1)
				(type default)
			)
			(layer "F.Fab")
		)
		(fp_line
			(start 0.120396 0.2794)
			(end -0.12065 0.2794)
			(stroke
				(width 0.1)
				(type default)
			)
			(layer "F.Fab")
		)
		(fp_line
			(start -0.12065 0.2794)
			(end -0.12065 0.3048)
			(stroke
				(width 0.1)
				(type default)
			)
			(layer "F.Fab")
		)
		(fp_line
			(start 0.67945 0.3048)
			(end 0.120396 0.3048)
			(stroke
				(width 0.1)
				(type default)
			)
			(layer "F.Fab")
		)
		(fp_line
			(start 0.120396 0.3048)
			(end 0.120396 0.2794)
			(stroke
				(width 0.1)
				(type default)
			)
			(layer "F.Fab")
		)
		(fp_line
			(start -0.12065 0.3048)
			(end -0.67945 0.3048)
			(stroke
				(width 0.1)
				(type default)
			)
			(layer "F.Fab")
		)
		(fp_line
			(start -0.67945 0.3048)
			(end -0.67945 -0.305054)
			(stroke
				(width 0.1)
				(type default)
			)
			(layer "F.Fab")
		)
		(pad "1" smd circle
			(at -0.40005 0 90)
			(size 0 0)
			(layers "F.Cu" "F.Mask" "F.Paste")
			(net "P12V_AUX")
		)
		(pad "2" smd circle
			(at 0.40005 0 90)
			(size 0 0)
			(layers "F.Cu" "F.Mask" "F.Paste")
			(net "P12V_OCP_OV_FB_1")
		)
	)
	(footprint ""
		(layer "F.Cu")
		(at 455.434192 -38.938962)
		(property "Reference" "U75"
			(at -1.778 -1.819148 0)
			(unlocked yes)
			(layer "F.SilkS")
			(effects
				(font
					(size 0.7874 0.5842)
					(thickness 0.1524)
				)
				(justify left)
			)
		)
		(property "Value" ""
			(at 0 0 0)
			(layer "F.Fab")
			(effects
				(font
					(size 1.27 1.27)
				)
			)
		)
		(duplicate_pad_numbers_are_jumpers no)
		(fp_line
			(start -1.695958 -1.124966)
			(end 1.695958 -1.124966)
			(stroke
				(width 0.1524)
				(type default)
			)
			(layer "F.SilkS")
		)
		(fp_line
			(start -1.695958 1.124966)
			(end -1.695958 -1.124966)
			(stroke
				(width 0.1524)
				(type default)
			)
			(layer "F.SilkS")
		)
		(fp_line
			(start 1.695958 -1.124966)
			(end 1.695958 1.124966)
			(stroke
				(width 0.1524)
				(type default)
			)
			(layer "F.SilkS")
		)
		(fp_line
			(start 1.695958 1.124966)
			(end -1.695958 1.124966)
			(stroke
				(width 0.1524)
				(type default)
			)
			(layer "F.SilkS")
		)
		(fp_poly
			(pts
				(xy -2.4892 -0.340106) (xy -2.4892 -0.959866) (xy -1.86944 -0.649986)
			)
			(stroke
				(width 0)
				(type default)
			)
			(fill yes)
			(layer "F.SilkS")
		)
		(fp_line
			(start -0.674878 -1.124966)
			(end 0.674878 -1.124966)
			(stroke
				(width 0.1)
				(type default)
			)
			(layer "F.Fab")
		)
		(fp_line
			(start -0.674878 1.124966)
			(end -0.674878 -1.124966)
			(stroke
				(width 0.1)
				(type default)
			)
			(layer "F.Fab")
		)
		(fp_line
			(start 0.674878 -1.124966)
			(end 0.674878 1.124966)
			(stroke
				(width 0.1)
				(type default)
			)
			(layer "F.Fab")
		)
		(fp_line
			(start 0.674878 1.124966)
			(end -0.674878 1.124966)
			(stroke
				(width 0.1)
				(type default)
			)
			(layer "F.Fab")
		)
		(fp_poly
			(pts
				(xy -2.4892 -0.959866) (xy -1.86944 -0.649986) (xy -2.4892 -0.340106)
			)
			(stroke
				(width 0)
				(type default)
			)
			(fill yes)
			(layer "F.Fab")
		)
		(pad "1" smd rect
			(at -0.94488 -0.649986 90)
			(size 0.3556 1.2446)
			(layers "F.Cu" "F.Mask" "F.Paste")
			(net "Net_1914")
		)
		(pad "2" smd rect
			(at -0.94488 0 90)
			(size 0.3556 1.2446)
			(layers "F.Cu" "F.Mask" "F.Paste")
			(net "RST_HP_OCP_V3_1_N")
		)
		(pad "3" smd rect
			(at -0.94488 0.649986 90)
			(size 0.3556 1.2446)
			(layers "F.Cu" "F.Mask" "F.Paste")
			(net "GND")
		)
		(pad "4" smd rect
			(at 0.94488 0.649986 90)
			(size 0.3556 1.2446)
			(layers "F.Cu" "F.Mask" "F.Paste")
			(net "RST_OCP_V3_1_BUF_N")
		)
		(pad "5" smd rect
			(at 0.94488 -0.649986 90)
			(size 0.3556 1.2446)
			(layers "F.Cu" "F.Mask" "F.Paste")
			(net "P3V3_AUX")
		)
	)
)
